(kicad_pcb
	(version 20241229)
	(generator "pcbnew")
	(generator_version "9.0")
	(general
		(thickness 1.61)
		(legacy_teardrops no)
	)
	(paper "A3")
	(title_block
		(title "RDIMM DDR5 Tester")
		(date "2026-05-21")
		(rev "2.2.0")
		(company "Antmicro")
		(comment 9 "footprints 785-788 of 796")
	)
	(layers
		(0 "F.Cu" signal)
		(4 "In1.Cu" power)
		(6 "In2.Cu" mixed)
		(8 "In3.Cu" power)
		(10 "In4.Cu" mixed)
		(12 "In5.Cu" power)
		(14 "In6.Cu" mixed)
		(16 "In7.Cu" power)
		(18 "In8.Cu" power)
		(20 "In9.Cu" mixed)
		(22 "In10.Cu" power)
		(2 "B.Cu" signal)
		(9 "F.Adhes" user "F.Adhesive")
		(11 "B.Adhes" user "B.Adhesive")
		(13 "F.Paste" user)
		(15 "B.Paste" user)
		(5 "F.SilkS" user "F.Silkscreen")
		(7 "B.SilkS" user "B.Silkscreen")
		(1 "F.Mask" user)
		(3 "B.Mask" user)
		(17 "Dwgs.User" user "User.Drawings")
		(19 "Cmts.User" user "User.Comments")
		(21 "Eco1.User" user "User.Eco1")
		(23 "Eco2.User" user "User.Eco2")
		(25 "Edge.Cuts" user)
		(27 "Margin" user)
		(31 "F.CrtYd" user "F.Courtyard")
		(29 "B.CrtYd" user "B.Courtyard")
		(35 "F.Fab" user)
		(33 "B.Fab" user)
	)
	(footprint "antmicro-footprints:C_0402_1005Metric_EIA"
		(layer "B.Cu")
		(at 187 160.5 90)
		(descr "Capacitor SMD 0402 (1005 Metric), square (rectangular) end terminal, IPC_7351 nominal, (Body size source: IPC-SM-782 page 76, https://www.pcb-3d.com/wordpress/wp-content/uploads/ipc-sm-782a_amendment_1_and_2.pdf)")
		(tags "capacitor 0402")
		(property "Reference" "C100"
			(at 8.725 -30.675 90)
			(layer "B.SilkS")
			(effects
				(font
					(size 0.7 0.7)
					(thickness 0.15)
				)
				(justify right bottom mirror)
			)
		)
		(property "Value" "C_100n_0402"
			(at 0 -1.169 90)
			(layer "B.Fab")
			(effects
				(font
					(size 0.7 0.7)
					(thickness 0.15)
				)
				(justify right bottom mirror)
			)
		)
		(property "Datasheet" "https://www.murata.com/products/productdetail?partno=GRM155R61H104KE14%23"
			(at 0 0 90)
			(layer "F.Fab")
			(hide yes)
			(effects
				(font
					(size 1.27 1.27)
					(thickness 0.15)
				)
			)
		)
		(property "MPN" "GRM155R61H104KE14D"
			(at 0 0 90)
			(unlocked yes)
			(layer "B.Fab")
			(hide yes)
			(effects
				(font
					(size 1 1)
					(thickness 0.15)
				)
				(justify mirror)
			)
		)
		(property "Manufacturer" "Murata"
			(at 0 0 90)
			(unlocked yes)
			(layer "B.Fab")
			(hide yes)
			(effects
				(font
					(size 1 1)
					(thickness 0.15)
				)
				(justify mirror)
			)
		)
		(property "License" "Apache-2.0"
			(at 0 0 90)
			(unlocked yes)
			(layer "B.Fab")
			(hide yes)
			(effects
				(font
					(size 1 1)
					(thickness 0.15)
				)
				(justify mirror)
			)
		)
		(property "Author" "Antmicro"
			(at 0 0 90)
			(unlocked yes)
			(layer "B.Fab")
			(hide yes)
			(effects
				(font
					(size 1 1)
					(thickness 0.15)
				)
				(justify mirror)
			)
		)
		(property "Val" "100n"
			(at 0 0 90)
			(unlocked yes)
			(layer "B.Fab")
			(hide yes)
			(effects
				(font
					(size 1 1)
					(thickness 0.15)
				)
				(justify mirror)
			)
		)
		(property "Voltage" "50V"
			(at 0 0 90)
			(unlocked yes)
			(layer "B.Fab")
			(hide yes)
			(effects
				(font
					(size 1 1)
					(thickness 0.15)
				)
				(justify mirror)
			)
		)
		(property "Dielectric" "X5R"
			(at 0 0 90)
			(unlocked yes)
			(layer "B.Fab")
			(hide yes)
			(effects
				(font
					(size 1 1)
					(thickness 0.15)
				)
				(justify mirror)
			)
		)
		(sheetname "/FPGA power/")
		(sheetfile "fpga-power.kicad_sch")
		(attr smd)
		(fp_rect
			(start -0.95 0.45)
			(end 0.95 -0.45)
			(stroke
				(width 0.05)
				(type default)
			)
			(fill no)
			(layer "B.CrtYd")
		)
		(fp_line
			(start 0.498 -0.248)
			(end -0.5 -0.248)
			(stroke
				(width 0.15)
				(type solid)
			)
			(layer "B.Fab")
		)
		(fp_line
			(start -0.5 -0.248)
			(end -0.5 0.25)
			(stroke
				(width 0.15)
				(type solid)
			)
			(layer "B.Fab")
		)
		(fp_line
			(start 0.498 0.25)
			(end 0.498 -0.248)
			(stroke
				(width 0.15)
				(type solid)
			)
			(layer "B.Fab")
		)
		(fp_line
			(start -0.5 0.25)
			(end 0.498 0.25)
			(stroke
				(width 0.15)
				(type solid)
			)
			(layer "B.Fab")
		)
		(fp_text user "Author: Antmicro"
			(at -0.9656 -5.569 270)
			(layer "B.Fab")
			(effects
				(font
					(size 0.7 0.7)
					(thickness 0.15)
				)
				(justify left bottom mirror)
			)
		)
		(fp_text user "License: Apache-2.0"
			(at -0.9656 -4.369 270)
			(layer "B.Fab")
			(effects
				(font
					(size 0.7 0.7)
					(thickness 0.15)
				)
				(justify left bottom mirror)
			)
		)
		(fp_text user "${REFERENCE}"
			(at -0.9656 -3.169 270)
			(layer "B.Fab")
			(effects
				(font
					(size 0.7 0.7)
					(thickness 0.15)
				)
				(justify left bottom mirror)
			)
		)
		(pad "1" smd roundrect
			(at -0.5 0)
			(size 0.6 0.6)
			(layers "B.Cu" "B.Mask" "B.Paste")
			(roundrect_rratio 0.25)
			(net 1 "GND")
			(pintype "passive")
		)
		(pad "2" smd roundrect
			(at 0.498 0 90)
			(size 0.6 0.6)
			(layers "B.Cu" "B.Mask" "B.Paste")
			(roundrect_rratio 0.25)
			(net 820 "+0V9_MGTAVCC")
			(pintype "passive")
		)
	)
	(footprint "antmicro-footprints:C_0402_1005Metric"
		(layer "B.Cu")
		(at 211.91 154.425)
		(descr "Capacitor SMD 0402")
		(tags "capacitor SMD 0402")
		(property "Reference" "C5"
			(at 0.99 0.465 0)
			(layer "B.SilkS")
			(effects
				(font
					(size 0.7 0.7)
					(thickness 0.15)
				)
				(justify right bottom mirror)
			)
		)
		(property "Value" "C_100n_0402"
			(at -1.022927 -2.155213 0)
			(layer "B.Fab")
			(effects
				(font
					(size 0.7 0.7)
					(thickness 0.15)
				)
				(justify right bottom mirror)
			)
		)
		(property "Datasheet" "https://www.murata.com/products/productdetail?partno=GRM155R61H104KE14%23"
			(at 0 0 0)
			(layer "F.Fab")
			(hide yes)
			(effects
				(font
					(size 1.27 1.27)
					(thickness 0.15)
				)
			)
		)
		(property "Manufacturer" "Murata"
			(at 0 0 0)
			(unlocked yes)
			(layer "B.Fab")
			(hide yes)
			(effects
				(font
					(size 1 1)
					(thickness 0.15)
				)
				(justify mirror)
			)
		)
		(property "MPN" "GRM155R61H104KE14D"
			(at 0 0 0)
			(unlocked yes)
			(layer "B.Fab")
			(hide yes)
			(effects
				(font
					(size 1 1)
					(thickness 0.15)
				)
				(justify mirror)
			)
		)
		(property "Val" "100n"
			(at 0 0 0)
			(unlocked yes)
			(layer "B.Fab")
			(hide yes)
			(effects
				(font
					(size 1 1)
					(thickness 0.15)
				)
				(justify mirror)
			)
		)
		(property "License" "Apache-2.0"
			(at 0 0 0)
			(unlocked yes)
			(layer "B.Fab")
			(hide yes)
			(effects
				(font
					(size 1 1)
					(thickness 0.15)
				)
				(justify mirror)
			)
		)
		(property "Author" "Antmicro"
			(at 0 0 0)
			(unlocked yes)
			(layer "B.Fab")
			(hide yes)
			(effects
				(font
					(size 1 1)
					(thickness 0.15)
				)
				(justify mirror)
			)
		)
		(property "Voltage" "50V"
			(at 0 0 0)
			(unlocked yes)
			(layer "B.Fab")
			(hide yes)
			(effects
				(font
					(size 1 1)
					(thickness 0.15)
				)
				(justify mirror)
			)
		)
		(property "Dielectric" "X5R"
			(at 0 0 0)
			(unlocked yes)
			(layer "B.Fab")
			(hide yes)
			(effects
				(font
					(size 1 1)
					(thickness 0.15)
				)
				(justify mirror)
			)
		)
		(sheetname "/HyperRAM + QSPI Flash/")
		(sheetfile "hyperram-flash.kicad_sch")
		(attr smd)
		(fp_rect
			(start -0.925 0.47)
			(end 0.925 -0.47)
			(stroke
				(width 0.05)
				(type default)
			)
			(fill no)
			(layer "B.CrtYd")
		)
		(fp_line
			(start -0.494 -0.248)
			(end -0.494 0.25)
			(stroke
				(width 0.15)
				(type solid)
			)
			(layer "B.Fab")
		)
		(fp_line
			(start -0.494 0.25)
			(end 0.504 0.25)
			(stroke
				(width 0.15)
				(type solid)
			)
			(layer "B.Fab")
		)
		(fp_line
			(start 0.504 -0.248)
			(end -0.494 -0.248)
			(stroke
				(width 0.15)
				(type solid)
			)
			(layer "B.Fab")
		)
		(fp_line
			(start 0.504 0.25)
			(end 0.504 -0.248)
			(stroke
				(width 0.15)
				(type solid)
			)
			(layer "B.Fab")
		)
		(fp_text user "License: Apache-2.0"
			(at -0.939 -5.799 180)
			(layer "B.Fab")
			(effects
				(font
					(size 0.7 0.7)
					(thickness 0.15)
				)
				(justify left bottom mirror)
			)
		)
		(fp_text user "${REFERENCE}"
			(at -0.939 -4.599 180)
			(layer "B.Fab")
			(effects
				(font
					(size 0.7 0.7)
					(thickness 0.15)
				)
				(justify left bottom mirror)
			)
		)
		(fp_text user "Author: Antmicro"
			(at -0.939 -3.399 180)
			(layer "B.Fab")
			(effects
				(font
					(size 0.7 0.7)
					(thickness 0.15)
				)
				(justify left bottom mirror)
			)
		)
		(pad "1" smd roundrect
			(at -0.48 0)
			(size 0.59 0.64)
			(layers "B.Cu" "B.Mask" "B.Paste")
			(roundrect_rratio 0.25)
			(net 797 "+1V8")
			(pintype "passive")
		)
		(pad "2" smd roundrect
			(at 0.48 0)
			(size 0.59 0.64)
			(layers "B.Cu" "B.Mask" "B.Paste")
			(roundrect_rratio 0.25)
			(net 1 "GND")
			(pintype "passive")
		)
	)
	(footprint "antmicro-footprints:R_0402_1005Metric"
		(layer "B.Cu")
		(at 128.879 102.638 180)
		(descr "Resistor SMD 0402")
		(tags "resistor SMD 0402")
		(property "Reference" "R233"
			(at -1.122484 0.772697 0)
			(layer "B.SilkS")
			(effects
				(font
					(size 0.7 0.7)
					(thickness 0.15)
				)
				(justify left bottom mirror)
			)
		)
		(property "Value" "R_49R9_0402"
			(at -1.011843 -1.772047 0)
			(layer "B.Fab")
			(effects
				(font
					(size 0.7 0.7)
					(thickness 0.15)
				)
				(justify left bottom mirror)
			)
		)
		(property "Datasheet" "https://www.bourns.com/docs/product-datasheets/cr.pdf"
			(at 0 0 180)
			(layer "F.Fab")
			(hide yes)
			(effects
				(font
					(size 1.27 1.27)
					(thickness 0.15)
				)
			)
		)
		(property "MPN" "CR0402-FX-49R9GLF"
			(at 0 0 180)
			(unlocked yes)
			(layer "B.Fab")
			(hide yes)
			(effects
				(font
					(size 1 1)
					(thickness 0.15)
				)
				(justify mirror)
			)
		)
		(property "Manufacturer" "Bourns"
			(at 0 0 180)
			(unlocked yes)
			(layer "B.Fab")
			(hide yes)
			(effects
				(font
					(size 1 1)
					(thickness 0.15)
				)
				(justify mirror)
			)
		)
		(property "License" "Apache-2.0"
			(at 0 0 180)
			(unlocked yes)
			(layer "B.Fab")
			(hide yes)
			(effects
				(font
					(size 1 1)
					(thickness 0.15)
				)
				(justify mirror)
			)
		)
		(property "Author" "Antmicro"
			(at 0 0 180)
			(unlocked yes)
			(layer "B.Fab")
			(hide yes)
			(effects
				(font
					(size 1 1)
					(thickness 0.15)
				)
				(justify mirror)
			)
		)
		(property "Val" "49R9"
			(at 0 0 180)
			(unlocked yes)
			(layer "B.Fab")
			(hide yes)
			(effects
				(font
					(size 1 1)
					(thickness 0.15)
				)
				(justify mirror)
			)
		)
		(property "Tolerance" "1%"
			(at 0 0 180)
			(unlocked yes)
			(layer "B.Fab")
			(hide yes)
			(effects
				(font
					(size 1 1)
					(thickness 0.15)
				)
				(justify mirror)
			)
		)
		(sheetname "/Debug FTDI + VNA/")
		(sheetfile "debug-ftdi.kicad_sch")
		(attr smd)
		(fp_rect
			(start -0.925 0.47)
			(end 0.925 -0.47)
			(stroke
				(width 0.05)
				(type default)
			)
			(fill no)
			(layer "B.CrtYd")
		)
		(fp_rect
			(start -0.5 0.25)
			(end 0.5 -0.25)
			(stroke
				(width 0.15)
				(type solid)
			)
			(fill no)
			(layer "B.Fab")
		)
		(fp_text user "Author: Antmicro"
			(at -0.95 -4.169 0)
			(layer "B.Fab")
			(effects
				(font
					(size 0.7 0.7)
					(thickness 0.15)
				)
				(justify left bottom mirror)
			)
		)
		(fp_text user "License: Apache-2.0"
			(at -0.95 -5.169 0)
			(layer "B.Fab")
			(effects
				(font
					(size 0.7 0.7)
					(thickness 0.15)
				)
				(justify left bottom mirror)
			)
		)
		(fp_text user "${REFERENCE}"
			(at -0.95 -3.168 0)
			(layer "B.Fab")
			(effects
				(font
					(size 0.7 0.7)
					(thickness 0.15)
				)
				(justify left bottom mirror)
			)
		)
		(pad "1" smd roundrect
			(at -0.48 0 180)
			(size 0.59 0.64)
			(layers "B.Cu" "B.Mask" "B.Paste")
			(roundrect_rratio 0.25)
			(net 1 "GND")
			(pintype "passive")
		)
		(pad "2" smd roundrect
			(at 0.48 0 180)
			(size 0.59 0.64)
			(layers "B.Cu" "B.Mask" "B.Paste")
			(roundrect_rratio 0.25)
			(net 370 "Net-(J14-Pad1)")
			(pintype "passive")
		)
	)
	(footprint "antmicro-footprints:DFN-6-1EP_2x2mm_P0.65mm_EP1x1.6mm"
		(layer "B.Cu")
		(at 206.75 138.8045 180)
		(descr "6-Lead Plastic Dual Flat, No Lead Package - 2x2x0.9 mm Body")
		(tags "DFN")
		(property "Reference" "U12"
			(at -2.55 0.0125 0)
			(layer "B.SilkS")
			(effects
				(font
					(size 0.7 0.7)
					(thickness 0.15)
				)
				(justify mirror)
			)
		)
		(property "Value" "MCP4726A0T_DFN"
			(at 0 -2.1 0)
			(layer "B.Fab")
			(effects
				(font
					(size 0.7 0.7)
					(thickness 0.15)
				)
				(justify left bottom mirror)
			)
		)
		(property "Datasheet" "https://ww1.microchip.com/downloads/en/DeviceDoc/22272C.pdf"
			(at 0 0 0)
			(layer "B.Fab")
			(hide yes)
			(effects
				(font
					(size 1.27 1.27)
					(thickness 0.15)
				)
				(justify mirror)
			)
		)
		(property "MPN" "MCP4726A0T-E/MAY"
			(at 0 0 0)
			(unlocked yes)
			(layer "B.Fab")
			(hide yes)
			(effects
				(font
					(size 1 1)
					(thickness 0.15)
				)
				(justify mirror)
			)
		)
		(property "Manufacturer" "Microchip Technology"
			(at 0 0 0)
			(unlocked yes)
			(layer "B.Fab")
			(hide yes)
			(effects
				(font
					(size 1 1)
					(thickness 0.15)
				)
				(justify mirror)
			)
		)
		(property "Author" "Antmicro"
			(at 0 0 0)
			(unlocked yes)
			(layer "B.Fab")
			(hide yes)
			(effects
				(font
					(size 1 1)
					(thickness 0.15)
				)
				(justify mirror)
			)
		)
		(property "License" "Apache-2.0"
			(at 0 0 0)
			(unlocked yes)
			(layer "B.Fab")
			(hide yes)
			(effects
				(font
					(size 1 1)
					(thickness 0.15)
				)
				(justify mirror)
			)
		)
		(property ki_fp_filters "DFN6_2x2MC_MCH DFN6_2x2MC_MCH-M DFN6_2x2MC_MCH-L")
		(sheetname "/Supply/")
		(sheetfile "supply.kicad_sch")
		(attr smd)
		(fp_line
			(start 1.075 1.1)
			(end 1.075 0.925)
			(stroke
				(width 0.15)
				(type solid)
			)
			(layer "B.SilkS")
		)
		(fp_line
			(start 1.075 -0.9375)
			(end 1.075 -1.1125)
			(stroke
				(width 0.15)
				(type solid)
			)
			(layer "B.SilkS")
		)
		(fp_line
			(start -1.075 1.1)
			(end 1.075 1.1)
			(stroke
				(width 0.15)
				(type solid)
			)
			(layer "B.SilkS")
		)
		(fp_line
			(start -1.075 1.1)
			(end -1.075 0.925)
			(stroke
				(width 0.15)
				(type solid)
			)
			(layer "B.SilkS")
		)
		(fp_line
			(start -1.075 -0.9375)
			(end -1.075 -1.1125)
			(stroke
				(width 0.15)
				(type solid)
			)
			(layer "B.SilkS")
		)
		(fp_line
			(start -1.075 -1.1125)
			(end 1.075 -1.1125)
			(stroke
				(width 0.15)
				(type solid)
			)
			(layer "B.SilkS")
		)
		(fp_circle
			(center -1.325 1.04571)
			(end -1.275 1.04571)
			(stroke
				(width 0.15)
				(type solid)
			)
			(fill yes)
			(layer "B.SilkS")
		)
		(fp_rect
			(start -1.405 1.25)
			(end 1.405 -1.225)
			(stroke
				(width 0.05)
				(type solid)
			)
			(fill no)
			(layer "B.CrtYd")
		)
		(fp_line
			(start -1 0.5)
			(end -0.5 1)
			(stroke
				(width 0.15)
				(type solid)
			)
			(layer "B.Fab")
		)
		(fp_rect
			(start 1 -1)
			(end -1 1)
			(stroke
				(width 0.15)
				(type solid)
			)
			(fill no)
			(layer "B.Fab")
		)
		(fp_text user "${REFERENCE}"
			(at -1.405 -3.4 0)
			(layer "B.Fab")
			(effects
				(font
					(size 0.7 0.7)
					(thickness 0.15)
				)
				(justify left bottom mirror)
			)
		)
		(fp_text user "License: Apache-2.0"
			(at -1.405 -5.799 0)
			(layer "B.Fab")
			(effects
				(font
					(size 0.7 0.7)
					(thickness 0.15)
				)
				(justify left bottom mirror)
			)
		)
		(fp_text user "Author: Antmicro"
			(at -1.405 -4.6 0)
			(layer "B.Fab")
			(effects
				(font
					(size 0.7 0.7)
					(thickness 0.15)
				)
				(justify left bottom mirror)
			)
		)
		(pad "" smd rect
			(at 0 -0.4 180)
			(size 0.82 0.63)
			(layers "B.Paste")
		)
		(pad "" smd rect
			(at 0 0.402 180)
			(size 0.82 0.63)
			(layers "B.Paste")
		)
		(pad "1" smd rect
			(at -1.051 0.652 180)
			(size 0.65 0.35)
			(layers "B.Cu" "B.Mask" "B.Paste")
			(net 687 "VDDQ")
			(pinfunction "VREF")
			(pintype "power_in")
		)
		(pad "2" smd rect
			(at -1.051 0 180)
			(size 0.65 0.35)
			(layers "B.Cu" "B.Mask" "B.Paste")
			(net 749 "/I^{2}C + I3C/PWR.SCL")
			(pinfunction "SCL")
			(pintype "input")
		)
		(pad "3" smd rect
			(at -1.051 -0.65 180)
			(size 0.65 0.35)
			(layers "B.Cu" "B.Mask" "B.Paste")
			(net 533 "/I^{2}C + I3C/PWR.SDA")
			(pinfunction "SDA")
			(pintype "bidirectional")
		)
		(pad "4" smd rect
			(at 1.05 -0.65 180)
			(size 0.65 0.35)
			(layers "B.Cu" "B.Mask" "B.Paste")
			(net 151 "+3V3")
			(pinfunction "VDD")
			(pintype "power_in")
		)
		(pad "5" smd rect
			(at 1.05 0 180)
			(size 0.65 0.35)
			(layers "B.Cu" "B.Mask" "B.Paste")
			(net 1 "GND")
			(pinfunction "GND")
			(pintype "power_in")
		)
		(pad "6" smd rect
			(at 1.05 0.652 180)
			(size 0.65 0.35)
			(layers "B.Cu" "B.Mask" "B.Paste")
			(net 825 "DAC_VREF")
			(pinfunction "VOUT")
			(pintype "output")
		)
		(pad "7" smd rect
			(at 0 0 180)
			(size 1 1.6)
			(layers "B.Cu" "B.Mask")
			(net 1 "GND")
			(pinfunction "SH")
			(pintype "power_in")
		)
	)
)
